(kicad_sch
	(version 20250114)
	(generator "eeschema")
	(generator_version "9.0")
	(paper "A3")
	(title_block
		(title "LPDDR5 Testbed")
		(date "2023-12-19")
		(rev "1.0.0")
	)
	(text "LPDDR5 Testbed"
		(exclude_from_sim no)
		(at 18.415 21.59 0)
		(effects
			(font
				(size 2.4892 2.4892)
				(thickness 0.4978)
				(bold yes)
			)
			(justify left bottom)
		)
	)
	(junction
		(at 212.09 85.09)
		(diameter 0)
		(color 0 0 0 0)
	)
	(wire
		(pts
			(xy 212.09 87.63) (xy 204.47 87.63)
		)
		(stroke
			(width 0)
			(type default)
		)
	)
	(wire
		(pts
			(xy 212.09 85.09) (xy 212.09 87.63)
		)
		(stroke
			(width 0)
			(type default)
		)
	)
	(wire
		(pts
			(xy 162.56 101.6) (xy 162.56 85.09)
		)
		(stroke
			(width 0)
			(type default)
		)
	)
	(bus
		(pts
			(xy 146.05 105.41) (xy 184.15 105.41)
		)
		(stroke
			(width 0)
			(type default)
		)
	)
	(wire
		(pts
			(xy 247.65 106.68) (xy 238.76 106.68)
		)
		(stroke
			(width 0)
			(type default)
		)
	)
	(wire
		(pts
			(xy 204.47 85.09) (xy 212.09 85.09)
		)
		(stroke
			(width 0)
			(type default)
		)
	)
	(wire
		(pts
			(xy 238.76 106.68) (xy 238.76 85.09)
		)
		(stroke
			(width 0)
			(type default)
		)
	)
	(wire
		(pts
			(xy 198.12 87.63) (xy 198.12 88.9)
		)
		(stroke
			(width 0)
			(type default)
		)
	)
	(bus
		(pts
			(xy 226.06 114.3) (xy 247.65 114.3)
		)
		(stroke
			(width 0)
			(type default)
		)
	)
	(wire
		(pts
			(xy 162.56 85.09) (xy 199.39 85.09)
		)
		(stroke
			(width 0)
			(type default)
		)
	)
	(bus
		(pts
			(xy 146.05 110.49) (xy 184.15 110.49)
		)
		(stroke
			(width 0)
			(type default)
		)
	)
	(bus
		(pts
			(xy 234.95 152.4) (xy 234.95 120.65)
		)
		(stroke
			(width 0)
			(type default)
		)
	)
	(wire
		(pts
			(xy 146.05 185.42) (xy 184.15 185.42)
		)
		(stroke
			(width 0)
			(type default)
		)
	)
	(wire
		(pts
			(xy 146.05 101.6) (xy 162.56 101.6)
		)
		(stroke
			(width 0)
			(type default)
		)
	)
	(bus
		(pts
			(xy 234.95 120.65) (xy 247.65 120.65)
		)
		(stroke
			(width 0)
			(type default)
		)
	)
	(wire
		(pts
			(xy 212.09 85.09) (xy 238.76 85.09)
		)
		(stroke
			(width 0)
			(type default)
		)
	)
	(bus
		(pts
			(xy 146.05 148.59) (xy 184.15 148.59)
		)
		(stroke
			(width 0)
			(type default)
		)
	)
	(bus
		(pts
			(xy 146.05 143.51) (xy 184.15 143.51)
		)
		(stroke
			(width 0)
			(type default)
		)
	)
	(bus
		(pts
			(xy 146.05 189.23) (xy 184.15 189.23)
		)
		(stroke
			(width 0)
			(type default)
		)
	)
	(wire
		(pts
			(xy 146.05 193.04) (xy 184.15 193.04)
		)
		(stroke
			(width 0)
			(type default)
		)
	)
	(wire
		(pts
			(xy 199.39 87.63) (xy 198.12 87.63)
		)
		(stroke
			(width 0)
			(type default)
		)
	)
	(bus
		(pts
			(xy 226.06 152.4) (xy 234.95 152.4)
		)
		(stroke
			(width 0)
			(type default)
		)
	)
	(symbol
		(lib_id "antmicroResistors0402:R_0R_0402")
		(at 199.39 85.09 0)
		(unit 1)
		(exclude_from_sim no)
		(in_bom yes)
		(on_board yes)
		(dnp no)
		(property "Reference" "R1"
			(at 205.74 83.82 0)
			(effects
				(font
					(size 1.27 1.27)
					(thickness 0.15)
				)
			)
		)
		(property "Value" "R_0R_0402"
			(at 219.71 97.79 0)
			(effects
				(font
					(size 1.27 1.27)
					(thickness 0.15)
				)
				(justify left bottom)
				(hide yes)
			)
		)
		(property "Footprint" "antmicro-footprints:R_0402_1005Metric"
			(at 219.71 100.33 0)
			(effects
				(font
					(size 1.27 1.27)
					(thickness 0.15)
				)
				(justify left bottom)
				(hide yes)
			)
		)
		(property "Datasheet" "https://industrial.panasonic.com/cdbs/www-data/pdf/RDA0000/AOA0000C301.pdf"
			(at 219.71 102.87 0)
			(effects
				(font
					(size 1.27 1.27)
					(thickness 0.15)
				)
				(justify left bottom)
				(hide yes)
			)
		)
		(property "Description" ""
			(at 199.39 85.09 0)
			(effects
				(font
					(size 1.27 1.27)
				)
			)
		)
		(property "MPN" "ERJ2GE0R00X"
			(at 219.71 105.41 0)
			(effects
				(font
					(size 1.27 1.27)
					(thickness 0.15)
				)
				(justify left bottom)
				(hide yes)
			)
		)
		(property "Manufacturer" "Panasonic"
			(at 219.71 107.95 0)
			(effects
				(font
					(size 1.27 1.27)
					(thickness 0.15)
				)
				(justify left bottom)
				(hide yes)
			)
		)
		(property "License" "Apache-2.0"
			(at 219.71 110.49 0)
			(effects
				(font
					(size 1.27 1.27)
					(thickness 0.15)
				)
				(justify left bottom)
				(hide yes)
			)
		)
		(property "Author" "Antmicro"
			(at 219.71 113.03 0)
			(effects
				(font
					(size 1.27 1.27)
					(thickness 0.15)
				)
				(justify left bottom)
				(hide yes)
			)
		)
		(property "Val" "0R"
			(at 196.85 83.82 0)
			(effects
				(font
					(size 1.27 1.27)
					(thickness 0.15)
				)
			)
		)
		(property "Tolerance" "~"
			(at 219.71 95.25 0)
			(effects
				(font
					(size 1.27 1.27)
				)
				(justify left bottom)
				(hide yes)
			)
		)
		(property "Current" "1A"
			(at 219.71 115.57 0)
			(effects
				(font
					(size 1.27 1.27)
					(thickness 0.15)
				)
				(justify left bottom)
				(hide yes)
			)
		)
		(pin "1"
		)
		(pin "2"
		)
		(instances
			(project ""
				(path ""
					(reference "R1")
					(unit 1)
				)
			)
		)
	)
	(symbol
		(lib_id "antmicroResistors0402:R_100R_0402")
		(at 199.39 87.63 0)
		(unit 1)
		(exclude_from_sim no)
		(in_bom no)
		(on_board yes)
		(dnp yes)
		(property "Reference" "R2"
			(at 204.47 86.36 0)
			(effects
				(font
					(size 1.27 1.27)
					(thickness 0.15)
				)
				(justify left)
			)
		)
		(property "Value" "R_100R_0402"
			(at 219.71 100.33 0)
			(effects
				(font
					(size 1.27 1.27)
					(thickness 0.15)
				)
				(justify left bottom)
				(hide yes)
			)
		)
		(property "Footprint" "antmicro-footprints:R_0402_1005Metric"
			(at 219.71 102.87 0)
			(effects
				(font
					(size 1.27 1.27)
					(thickness 0.15)
				)
				(justify left bottom)
				(hide yes)
			)
		)
		(property "Datasheet" "https://www.bourns.com/docs/product-datasheets/cr.pdf"
			(at 219.71 105.41 0)
			(effects
				(font
					(size 1.27 1.27)
					(thickness 0.15)
				)
				(justify left bottom)
				(hide yes)
			)
		)
		(property "Description" ""
			(at 199.39 87.63 0)
			(effects
				(font
					(size 1.27 1.27)
				)
			)
		)
		(property "MPN" "CR0402-FX-1000GLF"
			(at 219.71 107.95 0)
			(effects
				(font
					(size 1.27 1.27)
					(thickness 0.15)
				)
				(justify left bottom)
				(hide yes)
			)
		)
		(property "Manufacturer" "Bourns"
			(at 219.71 110.49 0)
			(effects
				(font
					(size 1.27 1.27)
					(thickness 0.15)
				)
				(justify left bottom)
				(hide yes)
			)
		)
		(property "License" "Apache-2.0"
			(at 219.71 113.03 0)
			(effects
				(font
					(size 1.27 1.27)
					(thickness 0.15)
				)
				(justify left bottom)
				(hide yes)
			)
		)
		(property "Author" "Antmicro"
			(at 219.71 115.57 0)
			(effects
				(font
					(size 1.27 1.27)
					(thickness 0.15)
				)
				(justify left bottom)
				(hide yes)
			)
		)
		(property "Val" "100R"
			(at 196.85 86.36 0)
			(effects
				(font
					(size 1.27 1.27)
					(thickness 0.15)
				)
			)
		)
		(property "Tolerance" "1%"
			(at 219.71 97.79 0)
			(effects
				(font
					(size 1.27 1.27)
				)
				(justify left bottom)
				(hide yes)
			)
		)
		(pin "1"
		)
		(pin "2"
		)
		(instances
			(project ""
				(path ""
					(reference "R2")
					(unit 1)
				)
			)
		)
	)
	(symbol
		(lib_id "antmicropower:GND")
		(at 198.12 88.9 0)
		(unit 1)
		(exclude_from_sim no)
		(in_bom yes)
		(on_board yes)
		(dnp no)
		(property "Reference" "#PWR0101"
			(at 207.01 91.44 0)
			(effects
				(font
					(size 1.27 1.27)
					(thickness 0.15)
				)
				(justify left bottom)
				(hide yes)
			)
		)
		(property "Value" "GND"
			(at 198.12 92.71 0)
			(effects
				(font
					(size 1.27 1.27)
					(thickness 0.15)
				)
			)
		)
		(property "Footprint" ""
			(at 207.01 96.52 0)
			(effects
				(font
					(size 1.27 1.27)
					(thickness 0.15)
				)
				(justify left bottom)
				(hide yes)
			)
		)
		(property "Datasheet" ""
			(at 207.01 101.6 0)
			(effects
				(font
					(size 1.27 1.27)
					(thickness 0.15)
				)
				(justify left bottom)
				(hide yes)
			)
		)
		(property "Description" ""
			(at 198.12 88.9 0)
			(effects
				(font
					(size 1.27 1.27)
				)
			)
		)
		(property "Author" "Antmicro"
			(at 207.01 96.52 0)
			(effects
				(font
					(size 1.27 1.27)
					(thickness 0.15)
				)
				(justify left bottom)
				(hide yes)
			)
		)
		(property "License" "Apache-2.0"
			(at 207.01 99.06 0)
			(effects
				(font
					(size 1.27 1.27)
					(thickness 0.15)
				)
				(justify left bottom)
				(hide yes)
			)
		)
		(pin "1"
		)
		(instances
			(project ""
				(path ""
					(reference "#PWR0101")
					(unit 1)
				)
			)
		)
	)
	(sheet
		(at 108.585 95.25)
		(size 37.465 107.95)
		(exclude_from_sim no)
		(in_bom yes)
		(on_board yes)
		(dnp no)
		(fields_autoplaced yes)
		(stroke
			(width 0)
			(type solid)
		)
		(fill
			(color 0 0 0 0.0000)
		)
		(property "Sheetname" "SODIMM"
			(at 108.585 94.5384 0)
			(effects
				(font
					(size 1.27 1.27)
				)
				(justify left bottom)
			)
		)
		(property "Sheetfile" "sodim.kicad_sch"
			(at 108.585 203.7846 0)
			(effects
				(font
					(size 1.27 1.27)
				)
				(justify left top)
			)
		)
		(pin "I2C{SDA,SCL}" bidirectional
			(at 146.05 189.23 0)
			(effects
				(font
					(size 1.27 1.27)
				)
				(justify right)
			)
		)
		(pin "PWR_EN" output
			(at 146.05 185.42 0)
			(effects
				(font
					(size 1.27 1.27)
				)
				(justify right)
			)
		)
		(pin "~{RESET}" output
			(at 146.05 101.6 0)
			(effects
				(font
					(size 1.27 1.27)
				)
				(justify right)
			)
		)
		(pin "LPDDR5_IN_B{LPDDR5}" output
			(at 146.05 148.59 0)
			(effects
				(font
					(size 1.27 1.27)
				)
				(justify right)
			)
		)
		(pin "LPDDR5_OUT_B{LPDDR5}" input
			(at 146.05 143.51 0)
			(effects
				(font
					(size 1.27 1.27)
				)
				(justify right)
			)
		)
		(pin "LPDDR5_IN_A{LPDDR5}" output
			(at 146.05 110.49 0)
			(effects
				(font
					(size 1.27 1.27)
				)
				(justify right)
			)
		)
		(pin "LPDDR5_OUT_A{LPDDR5}" input
			(at 146.05 105.41 0)
			(effects
				(font
					(size 1.27 1.27)
				)
				(justify right)
			)
		)
		(pin "PWRGD" input
			(at 146.05 193.04 0)
			(effects
				(font
					(size 1.27 1.27)
				)
				(justify right)
			)
		)
		(instances
			(project "lpddr5-testbed"
				(path ""
					(page "3")
				)
			)
		)
	)
	(sheet
		(at 247.65 101.6)
		(size 41.91 25.4)
		(exclude_from_sim no)
		(in_bom yes)
		(on_board yes)
		(dnp no)
		(fields_autoplaced yes)
		(stroke
			(width 0)
			(type solid)
		)
		(fill
			(color 0 0 0 0.0000)
		)
		(property "Sheetname" "LPDDR5"
			(at 247.65 100.8884 0)
			(effects
				(font
					(size 1.27 1.27)
				)
				(justify left bottom)
			)
		)
		(property "Sheetfile" "lpddr5.kicad_sch"
			(at 247.65 127.5846 0)
			(effects
				(font
					(size 1.27 1.27)
				)
				(justify left top)
			)
		)
		(pin "LPDDR5_B{LPDDR5}" bidirectional
			(at 247.65 120.65 180)
			(effects
				(font
					(size 1.27 1.27)
				)
				(justify left)
			)
		)
		(pin "LPDDR5_A{LPDDR5}" bidirectional
			(at 247.65 114.3 180)
			(effects
				(font
					(size 1.27 1.27)
				)
				(justify left)
			)
		)
		(pin "~{RESET}" input
			(at 247.65 106.68 180)
			(effects
				(font
					(size 1.27 1.27)
				)
				(justify left)
			)
		)
		(instances
			(project "lpddr5-testbed"
				(path ""
					(page "4")
				)
			)
		)
	)
	(sheet
		(at 184.15 177.8)
		(size 38.1 26.035)
		(exclude_from_sim no)
		(in_bom yes)
		(on_board yes)
		(dnp no)
		(fields_autoplaced yes)
		(stroke
			(width 0.1524)
			(type solid)
		)
		(fill
			(color 0 0 0 0.0000)
		)
		(property "Sheetname" "Power supply"
			(at 184.15 177.0884 0)
			(effects
				(font
					(size 1.27 1.27)
				)
				(justify left bottom)
			)
		)
		(property "Sheetfile" "power_supply.kicad_sch"
			(at 184.15 204.4196 0)
			(effects
				(font
					(size 1.27 1.27)
				)
				(justify left top)
			)
		)
		(pin "I2C{SDA,SCL}" bidirectional
			(at 184.15 189.23 180)
			(effects
				(font
					(size 1.27 1.27)
				)
				(justify left)
			)
		)
		(pin "PWR_EN" input
			(at 184.15 185.42 180)
			(effects
				(font
					(size 1.27 1.27)
				)
				(justify left)
			)
		)
		(pin "PWRGD" output
			(at 184.15 193.04 180)
			(effects
				(font
					(size 1.27 1.27)
				)
				(justify left)
			)
		)
		(instances
			(project "lpddr5-testbed"
				(path ""
					(page "5")
				)
			)
		)
	)
	(sheet
		(at 184.15 139.7)
		(size 41.91 25.4)
		(exclude_from_sim no)
		(in_bom yes)
		(on_board yes)
		(dnp no)
		(fields_autoplaced yes)
		(stroke
			(width 0)
			(type solid)
		)
		(fill
			(color 0 0 0 0.0000)
		)
		(property "Sheetname" "Translators1"
			(at 184.15 138.9884 0)
			(effects
				(font
					(size 1.27 1.27)
				)
				(justify left bottom)
			)
		)
		(property "Sheetfile" "translators.kicad_sch"
			(at 184.15 165.6846 0)
			(effects
				(font
					(size 1.27 1.27)
				)
				(justify left top)
			)
		)
		(pin "LPDDR5_DIE{LPDDR5}" output
			(at 226.06 152.4 0)
			(effects
				(font
					(size 1.27 1.27)
				)
				(justify right)
			)
		)
		(pin "LPDDR5_IN{LPDDR5}" input
			(at 184.15 148.59 180)
			(effects
				(font
					(size 1.27 1.27)
				)
				(justify left)
			)
		)
		(pin "LPDDR5_OUT{LPDDR5}" output
			(at 184.15 143.51 180)
			(effects
				(font
					(size 1.27 1.27)
				)
				(justify left)
			)
		)
		(instances
			(project "lpddr5-testbed"
				(path ""
					(page "6")
				)
			)
		)
	)
	(sheet
		(at 184.15 101.6)
		(size 41.91 25.4)
		(exclude_from_sim no)
		(in_bom yes)
		(on_board yes)
		(dnp no)
		(fields_autoplaced yes)
		(stroke
			(width 0)
			(type solid)
		)
		(fill
			(color 0 0 0 0.0000)
		)
		(property "Sheetname" "Translators"
			(at 184.15 100.8884 0)
			(effects
				(font
					(size 1.27 1.27)
				)
				(justify left bottom)
			)
		)
		(property "Sheetfile" "translators.kicad_sch"
			(at 184.15 127.5846 0)
			(effects
				(font
					(size 1.27 1.27)
				)
				(justify left top)
			)
		)
		(pin "LPDDR5_DIE{LPDDR5}" output
			(at 226.06 114.3 0)
			(effects
				(font
					(size 1.27 1.27)
				)
				(justify right)
			)
		)
		(pin "LPDDR5_OUT{LPDDR5}" output
			(at 184.15 105.41 180)
			(effects
				(font
					(size 1.27 1.27)
				)
				(justify left)
			)
		)
		(pin "LPDDR5_IN{LPDDR5}" input
			(at 184.15 110.49 180)
			(effects
				(font
					(size 1.27 1.27)
				)
				(justify left)
			)
		)
		(instances
			(project "lpddr5-testbed"
				(path ""
					(page "2")
				)
			)
		)
	)
	(sheet_instances
		(path "/"
			(page "1")
		)
	)
)
